(kicad_pcb
	(version 20241229)
	(generator "pcbnew")
	(generator_version "9.0")
	(general
		(thickness 1.59)
		(legacy_teardrops no)
	)
	(paper "A3")
	(title_block
		(title "usb-c-power-adapter")
		(date "2025-06-24")
		(rev "1.1.2")
		(company "Antmicro")
		(comment 9 "footprints 119-122 of 122")
	)
	(layers
		(0 "F.Cu" signal)
		(4 "In1.Cu" signal)
		(6 "In2.Cu" signal)
		(2 "B.Cu" signal)
		(9 "F.Adhes" user "F.Adhesive")
		(11 "B.Adhes" user "B.Adhesive")
		(13 "F.Paste" user)
		(15 "B.Paste" user)
		(5 "F.SilkS" user "F.Silkscreen")
		(7 "B.SilkS" user "B.Silkscreen")
		(1 "F.Mask" user)
		(3 "B.Mask" user)
		(17 "Dwgs.User" user "User.Drawings")
		(19 "Cmts.User" user "User.Comments")
		(21 "Eco1.User" user "User.Eco1")
		(23 "Eco2.User" user "User.Eco2")
		(25 "Edge.Cuts" user)
		(27 "Margin" user)
		(31 "F.CrtYd" user "F.Courtyard")
		(29 "B.CrtYd" user "B.Courtyard")
		(35 "F.Fab" user)
		(33 "B.Fab" user)
	)
	(footprint "antmicro-footprints:C_1206_3216Metric"
		(layer "B.Cu")
		(at 88.9 97.85 90)
		(descr "Capacitor SMD 1206")
		(tags "capacitor SMD 1206")
		(property "Reference" "C37"
			(at 22.158 -2.538 0)
			(layer "B.SilkS")
			(effects
				(font
					(size 0.7 0.7)
					(thickness 0.15)
				)
				(justify left bottom mirror)
			)
		)
		(property "Value" "C_47u_25V_1206"
			(at 0 -2.101 90)
			(layer "B.Fab")
			(effects
				(font
					(size 0.7 0.7)
					(thickness 0.15)
				)
				(justify right bottom mirror)
			)
		)
		(property "Datasheet" "https://product.tdk.com/en/search/capacitor/ceramic/mlcc/info?part_no=C3216X5R1E476M160AC"
			(at 0 0 90)
			(layer "F.Fab")
			(hide yes)
			(effects
				(font
					(size 1.27 1.27)
					(thickness 0.15)
				)
			)
		)
		(property "Description" "SMD Multilayer Ceramic Capacitor, 47 µF, 25 V, 1206 [3216 Metric], ± 20%, X5R"
			(at 0 0 90)
			(layer "F.Fab")
			(hide yes)
			(effects
				(font
					(size 1.27 1.27)
					(thickness 0.15)
				)
			)
		)
		(property "MPN" "C3216X5R1E476M160AC"
			(at 0 0 90)
			(unlocked yes)
			(layer "B.Fab")
			(hide yes)
			(effects
				(font
					(size 1 1)
					(thickness 0.15)
				)
				(justify mirror)
			)
		)
		(property "Val" "47u"
			(at 0 0 90)
			(unlocked yes)
			(layer "B.Fab")
			(hide yes)
			(effects
				(font
					(size 1 1)
					(thickness 0.15)
				)
				(justify mirror)
			)
		)
		(property "Voltage" "25V"
			(at 0 0 90)
			(unlocked yes)
			(layer "B.Fab")
			(hide yes)
			(effects
				(font
					(size 1 1)
					(thickness 0.15)
				)
				(justify mirror)
			)
		)
		(property "Author" "Antmicro"
			(at 0 0 90)
			(unlocked yes)
			(layer "B.Fab")
			(hide yes)
			(effects
				(font
					(size 1 1)
					(thickness 0.15)
				)
				(justify mirror)
			)
		)
		(property "License" "Apache-2.0"
			(at 0 0 90)
			(unlocked yes)
			(layer "B.Fab")
			(hide yes)
			(effects
				(font
					(size 1 1)
					(thickness 0.15)
				)
				(justify mirror)
			)
		)
		(property "Manufacturer" "TDK"
			(at 0 0 90)
			(unlocked yes)
			(layer "B.Fab")
			(hide yes)
			(effects
				(font
					(size 1 1)
					(thickness 0.15)
				)
				(justify mirror)
			)
		)
		(property "Dielectric" "X5R"
			(at 0 0 90)
			(unlocked yes)
			(layer "B.Fab")
			(hide yes)
			(effects
				(font
					(size 1 1)
					(thickness 0.15)
				)
				(justify mirror)
			)
		)
		(property "Public" "False"
			(at 0 0 90)
			(unlocked yes)
			(layer "B.Fab")
			(hide yes)
			(effects
				(font
					(size 1 1)
					(thickness 0.15)
				)
				(justify mirror)
			)
		)
		(sheetname "/DC-DC Converters/")
		(sheetfile "dc-dc_converters.kicad_sch")
		(attr smd)
		(fp_line
			(start -0.8 -0.901)
			(end 0.8 -0.901)
			(stroke
				(width 0.15)
				(type solid)
			)
			(layer "B.SilkS")
		)
		(fp_line
			(start -0.8 0.899)
			(end 0.8 0.899)
			(stroke
				(width 0.15)
				(type solid)
			)
			(layer "B.SilkS")
		)
		(fp_rect
			(start -2.325 1.15)
			(end 2.325 -1.15)
			(stroke
				(width 0.05)
				(type default)
			)
			(fill no)
			(layer "B.CrtYd")
		)
		(fp_rect
			(start -1.6 0.799)
			(end 1.6 -0.801)
			(stroke
				(width 0.15)
				(type solid)
			)
			(fill no)
			(layer "B.Fab")
		)
		(pad "1" smd roundrect
			(at -1.5 -0.001 90)
			(size 1.15 1.8)
			(layers "B.Cu" "B.Mask" "B.Paste")
			(roundrect_rratio 0.25)
			(net 2 "GND")
			(pintype "passive")
		)
		(pad "2" smd roundrect
			(at 1.5 -0.001 90)
			(size 1.15 1.8)
			(layers "B.Cu" "B.Mask" "B.Paste")
			(roundrect_rratio 0.25)
			(net 5 "+12V")
			(pintype "passive")
		)
	)
	(footprint "antmicro-footprints:L_1008_2520Metric"
		(layer "B.Cu")
		(at 83.85 80.1 180)
		(descr "Inductor SMD 1008 (2520 Metric)")
		(tags "inductor")
		(property "Reference" "L3"
			(at -1.748 1.487 0)
			(layer "B.SilkS")
			(effects
				(font
					(size 0.7 0.7)
					(thickness 0.15)
				)
				(justify left bottom mirror)
			)
		)
		(property "Value" "L_3u3_2.5A_1008"
			(at 0 -2.5 0)
			(layer "B.Fab")
			(effects
				(font
					(size 0.7 0.7)
					(thickness 0.15)
				)
				(justify left bottom mirror)
			)
		)
		(property "Datasheet" "https://product.tdk.com/system/files/dam/doc/product/inductor/inductor/smd/catalog/inductor_automotive_power_tfm252012alma_en.pdf"
			(at 0 0 180)
			(layer "F.Fab")
			(hide yes)
			(effects
				(font
					(size 1.27 1.27)
					(thickness 0.15)
				)
			)
		)
		(property "Description" "3.3 µH Shielded Thin Film Inductor 2 A 140mOhm Max 1008 (2520 Metric)"
			(at 0 0 180)
			(layer "F.Fab")
			(hide yes)
			(effects
				(font
					(size 1.27 1.27)
					(thickness 0.15)
				)
			)
		)
		(property "MPN" "TFM252012ALMA3R3MTAA"
			(at 0 0 180)
			(unlocked yes)
			(layer "B.Fab")
			(hide yes)
			(effects
				(font
					(size 1 1)
					(thickness 0.15)
				)
				(justify mirror)
			)
		)
		(property "ISat" "2.1 A"
			(at 0 0 180)
			(unlocked yes)
			(layer "B.Fab")
			(hide yes)
			(effects
				(font
					(size 1 1)
					(thickness 0.15)
				)
				(justify mirror)
			)
		)
		(property "IMax" "2.5 A"
			(at 0 0 180)
			(unlocked yes)
			(layer "B.Fab")
			(hide yes)
			(effects
				(font
					(size 1 1)
					(thickness 0.15)
				)
				(justify mirror)
			)
		)
		(property "Manufacturer" "TDK"
			(at 0 0 180)
			(unlocked yes)
			(layer "B.Fab")
			(hide yes)
			(effects
				(font
					(size 1 1)
					(thickness 0.15)
				)
				(justify mirror)
			)
		)
		(property "Val" "3u3/2.5A"
			(at 0 0 180)
			(unlocked yes)
			(layer "B.Fab")
			(hide yes)
			(effects
				(font
					(size 1 1)
					(thickness 0.15)
				)
				(justify mirror)
			)
		)
		(property "Size" "2.5x2.0"
			(at 0 0 180)
			(unlocked yes)
			(layer "B.Fab")
			(hide yes)
			(effects
				(font
					(size 1 1)
					(thickness 0.15)
				)
				(justify mirror)
			)
		)
		(property "Author" "Antmicro"
			(at 0 0 180)
			(unlocked yes)
			(layer "B.Fab")
			(hide yes)
			(effects
				(font
					(size 1 1)
					(thickness 0.15)
				)
				(justify mirror)
			)
		)
		(property "License" "Apache-2.0"
			(at 0 0 180)
			(unlocked yes)
			(layer "B.Fab")
			(hide yes)
			(effects
				(font
					(size 1 1)
					(thickness 0.15)
				)
				(justify mirror)
			)
		)
		(sheetname "/DC-DC Converters/")
		(sheetfile "dc-dc_converters.kicad_sch")
		(attr smd)
		(fp_line
			(start 0.261 1.111)
			(end -0.264 1.111)
			(stroke
				(width 0.15)
				(type solid)
			)
			(layer "B.SilkS")
		)
		(fp_line
			(start 0.261 -1.11)
			(end -0.264 -1.11)
			(stroke
				(width 0.15)
				(type solid)
			)
			(layer "B.SilkS")
		)
		(fp_rect
			(start -1.95 1.25)
			(end 1.95 -1.25)
			(stroke
				(width 0.05)
				(type solid)
			)
			(fill no)
			(layer "B.CrtYd")
		)
		(fp_line
			(start 1.249 0.999)
			(end -1.05 0.999)
			(stroke
				(width 0.15)
				(type solid)
			)
			(layer "B.Fab")
		)
		(fp_line
			(start 1.249 -0.997)
			(end 1.249 0.999)
			(stroke
				(width 0.15)
				(type solid)
			)
			(layer "B.Fab")
		)
		(fp_line
			(start -1.05 0.999)
			(end -1.25 0.8)
			(stroke
				(width 0.15)
				(type solid)
			)
			(layer "B.Fab")
		)
		(fp_line
			(start -1.25 0.8)
			(end -1.25 -0.997)
			(stroke
				(width 0.15)
				(type solid)
			)
			(layer "B.Fab")
		)
		(fp_line
			(start -1.25 -0.997)
			(end 1.249 -0.997)
			(stroke
				(width 0.15)
				(type solid)
			)
			(layer "B.Fab")
		)
		(pad "1" smd roundrect
			(at -1.075 0 180)
			(size 1.25 2.2)
			(layers "B.Cu" "B.Mask" "B.Paste")
			(roundrect_rratio 0.1)
			(net 23 "Net-(U4-SW)")
			(pintype "passive")
		)
		(pad "2" smd roundrect
			(at 1.075 0 180)
			(size 1.25 2.2)
			(layers "B.Cu" "B.Mask" "B.Paste")
			(roundrect_rratio 0.1)
			(net 1 "+3V3")
			(pintype "passive")
		)
	)
	(footprint "antmicro-footprints:R_0402_1005Metric"
		(layer "B.Cu")
		(at 87.401 86.7 -90)
		(descr "Resistor SMD 0402")
		(tags "resistor SMD 0402")
		(property "Reference" "R23"
			(at -1.083 -3.101 270)
			(layer "B.SilkS")
			(effects
				(font
					(size 0.7 0.7)
					(thickness 0.15)
				)
				(justify left bottom mirror)
			)
		)
		(property "Value" "R_15k_0402"
			(at -1.011843 -1.772047 90)
			(layer "B.Fab")
			(effects
				(font
					(size 0.7 0.7)
					(thickness 0.15)
				)
				(justify left bottom mirror)
			)
		)
		(property "Datasheet" "https://www.bourns.com/docs/product-datasheets/cr.pdf"
			(at 0 0 270)
			(layer "F.Fab")
			(hide yes)
			(effects
				(font
					(size 1.27 1.27)
					(thickness 0.15)
				)
			)
		)
		(property "Description" "SMD Chip Resistor, 15 kohm, ± 1%, 62.5 mW, 0402 [1005 Metric], Thick Film, General Purpose"
			(at 0 0 270)
			(layer "F.Fab")
			(hide yes)
			(effects
				(font
					(size 1.27 1.27)
					(thickness 0.15)
				)
			)
		)
		(property "MPN" "CR0402-FX-1502GLF"
			(at 0 0 270)
			(unlocked yes)
			(layer "B.Fab")
			(hide yes)
			(effects
				(font
					(size 1 1)
					(thickness 0.15)
				)
				(justify mirror)
			)
		)
		(property "Manufacturer" "Bourns"
			(at 0 0 270)
			(unlocked yes)
			(layer "B.Fab")
			(hide yes)
			(effects
				(font
					(size 1 1)
					(thickness 0.15)
				)
				(justify mirror)
			)
		)
		(property "License" "Apache-2.0"
			(at 0 0 270)
			(unlocked yes)
			(layer "B.Fab")
			(hide yes)
			(effects
				(font
					(size 1 1)
					(thickness 0.15)
				)
				(justify mirror)
			)
		)
		(property "Author" "Antmicro"
			(at 0 0 270)
			(unlocked yes)
			(layer "B.Fab")
			(hide yes)
			(effects
				(font
					(size 1 1)
					(thickness 0.15)
				)
				(justify mirror)
			)
		)
		(property "Val" "15k"
			(at 0 0 270)
			(unlocked yes)
			(layer "B.Fab")
			(hide yes)
			(effects
				(font
					(size 1 1)
					(thickness 0.15)
				)
				(justify mirror)
			)
		)
		(property "Tolerance" "1%"
			(at 0 0 270)
			(unlocked yes)
			(layer "B.Fab")
			(hide yes)
			(effects
				(font
					(size 1 1)
					(thickness 0.15)
				)
				(justify mirror)
			)
		)
		(sheetname "/DC-DC Converters/")
		(sheetfile "dc-dc_converters.kicad_sch")
		(attr smd)
		(fp_rect
			(start -0.925 0.47)
			(end 0.925 -0.47)
			(stroke
				(width 0.05)
				(type default)
			)
			(fill no)
			(layer "B.CrtYd")
		)
		(fp_rect
			(start -0.5 0.25)
			(end 0.5 -0.25)
			(stroke
				(width 0.15)
				(type solid)
			)
			(fill no)
			(layer "B.Fab")
		)
		(pad "1" smd roundrect
			(at -0.48 0 270)
			(size 0.59 0.64)
			(layers "B.Cu" "B.Mask" "B.Paste")
			(roundrect_rratio 0.25)
			(net 2 "GND")
			(pintype "passive")
		)
		(pad "2" smd roundrect
			(at 0.48 0 270)
			(size 0.59 0.64)
			(layers "B.Cu" "B.Mask" "B.Paste")
			(roundrect_rratio 0.25)
			(net 47 "Net-(U3-EN)")
			(pintype "passive")
		)
	)
	(footprint "antmicro-footprints:C_0402_1005Metric"
		(layer "B.Cu")
		(at 96.4 87.05 -90)
		(descr "Capacitor SMD 0402")
		(tags "capacitor SMD 0402")
		(property "Reference" "C41"
			(at -1.1 0.6 270)
			(layer "B.SilkS")
			(effects
				(font
					(size 0.7 0.7)
					(thickness 0.15)
				)
				(justify left bottom mirror)
			)
		)
		(property "Value" "C_1u_25V_0402"
			(at -1.022927 -2.155213 90)
			(layer "B.Fab")
			(effects
				(font
					(size 0.7 0.7)
					(thickness 0.15)
				)
				(justify left bottom mirror)
			)
		)
		(property "Datasheet" "https://www.murata.com/products/productdetail?partno=GRM155R61E105KE11%23"
			(at 0 0 270)
			(layer "F.Fab")
			(hide yes)
			(effects
				(font
					(size 1.27 1.27)
					(thickness 0.15)
				)
			)
		)
		(property "Description" "SMD Multilayer Ceramic Capacitor, 1 µF, 25 V, 0402 [1005 Metric], ± 10%, X5R, GRM Series"
			(at 0 0 270)
			(layer "F.Fab")
			(hide yes)
			(effects
				(font
					(size 1.27 1.27)
					(thickness 0.15)
				)
			)
		)
		(property "MPN" "GRM155R61E105KE11J"
			(at 0 0 270)
			(unlocked yes)
			(layer "B.Fab")
			(hide yes)
			(effects
				(font
					(size 1 1)
					(thickness 0.15)
				)
				(justify mirror)
			)
		)
		(property "Manufacturer" "Murata"
			(at 0 0 270)
			(unlocked yes)
			(layer "B.Fab")
			(hide yes)
			(effects
				(font
					(size 1 1)
					(thickness 0.15)
				)
				(justify mirror)
			)
		)
		(property "License" "Apache-2.0"
			(at 0 0 270)
			(unlocked yes)
			(layer "B.Fab")
			(hide yes)
			(effects
				(font
					(size 1 1)
					(thickness 0.15)
				)
				(justify mirror)
			)
		)
		(property "Author" "Antmicro"
			(at 0 0 270)
			(unlocked yes)
			(layer "B.Fab")
			(hide yes)
			(effects
				(font
					(size 1 1)
					(thickness 0.15)
				)
				(justify mirror)
			)
		)
		(property "Val" "1u"
			(at 0 0 270)
			(unlocked yes)
			(layer "B.Fab")
			(hide yes)
			(effects
				(font
					(size 1 1)
					(thickness 0.15)
				)
				(justify mirror)
			)
		)
		(property "Voltage" "25V"
			(at 0 0 270)
			(unlocked yes)
			(layer "B.Fab")
			(hide yes)
			(effects
				(font
					(size 1 1)
					(thickness 0.15)
				)
				(justify mirror)
			)
		)
		(property "Dielectric" "X5R"
			(at 0 0 270)
			(unlocked yes)
			(layer "B.Fab")
			(hide yes)
			(effects
				(font
					(size 1 1)
					(thickness 0.15)
				)
				(justify mirror)
			)
		)
		(sheetname "/DC-DC Converters/")
		(sheetfile "dc-dc_converters.kicad_sch")
		(attr smd)
		(fp_rect
			(start -0.925 0.47)
			(end 0.925 -0.47)
			(stroke
				(width 0.05)
				(type default)
			)
			(fill no)
			(layer "B.CrtYd")
		)
		(fp_line
			(start -0.494 0.25)
			(end -0.494 -0.248)
			(stroke
				(width 0.15)
				(type solid)
			)
			(layer "B.Fab")
		)
		(fp_line
			(start 0.504 0.25)
			(end -0.494 0.25)
			(stroke
				(width 0.15)
				(type solid)
			)
			(layer "B.Fab")
		)
		(fp_line
			(start -0.494 -0.248)
			(end 0.504 -0.248)
			(stroke
				(width 0.15)
				(type solid)
			)
			(layer "B.Fab")
		)
		(fp_line
			(start 0.504 -0.248)
			(end 0.504 0.25)
			(stroke
				(width 0.15)
				(type solid)
			)
			(layer "B.Fab")
		)
		(pad "1" smd roundrect
			(at -0.48 0 270)
			(size 0.59 0.64)
			(layers "B.Cu" "B.Mask" "B.Paste")
			(roundrect_rratio 0.25)
			(net 2 "GND")
			(pintype "passive")
		)
		(pad "2" smd roundrect
			(at 0.48 0 270)
			(size 0.59 0.64)
			(layers "B.Cu" "B.Mask" "B.Paste")
			(roundrect_rratio 0.25)
			(net 1 "+3V3")
			(pintype "passive")
		)
	)
)
